(kicad_pcb
	(version 20260206)
	(generator "pcbnew")
	(generator_version "10.0")
	(general
		(thickness 1.6)
		(legacy_teardrops no)
	)
	(paper "A4")
	(title_block
		(title "Bryce Canyon_IOM_IOC_16318-2_OCP.brd")
		(comment 1 "Bryce Canyon / footprints 818-824 of 1605")
	)
	(layers
		(0 "F.Cu" signal "TOP")
		(4 "In1.Cu" signal "L2GND")
		(6 "In2.Cu" signal "L3")
		(8 "In3.Cu" signal "L4VCC")
		(10 "In4.Cu" signal "L5VCC")
		(12 "In5.Cu" signal "L6")
		(14 "In6.Cu" signal "L7GND")
		(2 "B.Cu" signal "BOTTOM")
		(9 "F.Adhes" user "F.Adhesive")
		(11 "B.Adhes" user "B.Adhesive")
		(13 "F.Paste" user "Package Geometry/Pastemask Top")
		(15 "B.Paste" user "Package Geometry/Pastemask Bottom")
		(5 "F.SilkS" user "Ref Des/Silkscreen Top")
		(7 "B.SilkS" user "Ref Des/Silkscreen Bottom")
		(1 "F.Mask" user "Board Geometry/Soldermask Top")
		(3 "B.Mask" user "Board Geometry/Soldermask Bottom")
		(17 "Dwgs.User" user "User.Drawings")
		(19 "Cmts.User" user "User.Comments")
		(21 "Eco1.User" user "User.Eco1")
		(23 "Eco2.User" user "User.Eco2")
		(25 "Edge.Cuts" user "Board Geometry/Outline")
		(27 "Margin" user)
		(31 "F.CrtYd" user "Package Geometry/Place Bound Top")
		(29 "B.CrtYd" user "Package Geometry/Place Bound Bottom")
		(35 "F.Fab" user "Ref Des/Assembly Top")
		(33 "B.Fab" user "Ref Des/Assembly Bottom")
	)
	(footprint ""
		(layer "F.Cu")
		(at 174.4472 -64.8716 90)
		(property "Reference" "R581"
			(at 0 0 90)
			(layer "F.SilkS")
			(hide yes)
			(effects
				(font
					(size 1.27 1.27)
				)
			)
		)
		(property "Value" "2K2R2F-GP"
			(at 0.064008 -3.993896 90)
			(unlocked yes)
			(layer "F.Fab")
			(hide yes)
			(effects
				(font
					(size 1.016 1.016)
					(thickness 0.1524)
				)
			)
		)
		(property "Device Type" "R402H16"
			(at 0.064008 -5.517896 90)
			(unlocked yes)
			(layer "F.Fab")
			(hide yes)
			(effects
				(font
					(size 1.016 1.016)
					(thickness 0.1524)
				)
			)
		)
		(duplicate_pad_numbers_are_jumpers no)
		(fp_line
			(start 0.508 -0.9398)
			(end -0.508 -0.9398)
			(stroke
				(width 0.1524)
				(type default)
			)
			(layer "F.SilkS")
		)
		(fp_line
			(start -0.508 -0.9398)
			(end -0.508 0.9398)
			(stroke
				(width 0.1524)
				(type default)
			)
			(layer "F.SilkS")
		)
		(fp_rect
			(start -0.508 0.9398)
			(end 0.508 -0.9398)
			(stroke
				(width 0)
				(type default)
			)
			(fill no)
			(layer "F.CrtYd")
		)
		(fp_rect
			(start -0.508 0.9398)
			(end 0.508 -0.9398)
			(stroke
				(width 0)
				(type default)
			)
			(fill no)
			(layer "F.Fab")
		)
		(pad "1" smd custom
			(at 0 -0.4445 90)
			(size 0.1397 0.1397)
			(layers "F.Cu" "F.Mask" "F.Paste")
			(net "P1V8")
			(options
				(clearance outline)
				(anchor circle)
			)
			(primitives
				(gr_poly
					(pts
						(arc
							(start -0.1778 -0.2794)
							(mid -0.249642 -0.249642)
							(end -0.2794 -0.1778)
						)
						(arc
							(start -0.2794 0.1778)
							(mid -0.249642 0.249642)
							(end -0.1778 0.2794)
						)
						(arc
							(start 0.1778 0.2794)
							(mid 0.249642 0.249642)
							(end 0.2794 0.1778)
						)
						(arc
							(start 0.2794 -0.1778)
							(mid 0.249642 -0.249642)
							(end 0.1778 -0.2794)
						)
					)
					(width 0)
					(fill yes)
				)
			)
		)
		(pad "2" smd custom
			(at 0 0.4445 90)
			(size 0.1397 0.1397)
			(layers "F.Cu" "F.Mask" "F.Paste")
			(net "IOC_SDA_0")
			(options
				(clearance outline)
				(anchor circle)
			)
			(primitives
				(gr_poly
					(pts
						(arc
							(start -0.1778 -0.2794)
							(mid -0.249642 -0.249642)
							(end -0.2794 -0.1778)
						)
						(arc
							(start -0.2794 0.1778)
							(mid -0.249642 0.249642)
							(end -0.1778 0.2794)
						)
						(arc
							(start 0.1778 0.2794)
							(mid 0.249642 0.249642)
							(end 0.2794 0.1778)
						)
						(arc
							(start 0.2794 -0.1778)
							(mid 0.249642 -0.249642)
							(end 0.1778 -0.2794)
						)
					)
					(width 0)
					(fill yes)
				)
			)
		)
	)
	(footprint ""
		(layer "F.Cu")
		(at 207.333088 -99.984306 -90)
		(property "Reference" "R602"
			(at 0 0 270)
			(layer "F.SilkS")
			(hide yes)
			(effects
				(font
					(size 1.27 1.27)
				)
			)
		)
		(property "Value" "0R2J-2-GP"
			(at 0.064008 -3.993896 270)
			(unlocked yes)
			(layer "F.Fab")
			(hide yes)
			(effects
				(font
					(size 1.016 1.016)
					(thickness 0.1524)
				)
			)
		)
		(property "Device Type" "R402H16"
			(at 0.064008 -5.517896 270)
			(unlocked yes)
			(layer "F.Fab")
			(hide yes)
			(effects
				(font
					(size 1.016 1.016)
					(thickness 0.1524)
				)
			)
		)
		(duplicate_pad_numbers_are_jumpers no)
		(fp_line
			(start -0.508 -0.9398)
			(end -0.508 0.9398)
			(stroke
				(width 0.1524)
				(type default)
			)
			(layer "F.SilkS")
		)
		(fp_line
			(start 0.508 -0.9398)
			(end -0.508 -0.9398)
			(stroke
				(width 0.1524)
				(type default)
			)
			(layer "F.SilkS")
		)
		(fp_rect
			(start -0.508 0.9398)
			(end 0.508 -0.9398)
			(stroke
				(width 0)
				(type default)
			)
			(fill no)
			(layer "F.CrtYd")
		)
		(fp_rect
			(start -0.508 0.9398)
			(end 0.508 -0.9398)
			(stroke
				(width 0)
				(type default)
			)
			(fill no)
			(layer "F.Fab")
		)
		(pad "1" smd custom
			(at 0 -0.4445 270)
			(size 0.1397 0.1397)
			(layers "F.Cu" "F.Mask" "F.Paste")
			(net "IOC_EEPROM_WP")
			(options
				(clearance outline)
				(anchor circle)
			)
			(primitives
				(gr_poly
					(pts
						(arc
							(start -0.1778 -0.2794)
							(mid -0.249642 -0.249642)
							(end -0.2794 -0.1778)
						)
						(arc
							(start -0.2794 0.1778)
							(mid -0.249642 0.249642)
							(end -0.1778 0.2794)
						)
						(arc
							(start 0.1778 0.2794)
							(mid 0.249642 0.249642)
							(end 0.2794 0.1778)
						)
						(arc
							(start 0.2794 -0.1778)
							(mid 0.249642 -0.249642)
							(end 0.1778 -0.2794)
						)
					)
					(width 0)
					(fill yes)
				)
			)
		)
		(pad "2" smd custom
			(at 0 0.4445 270)
			(size 0.1397 0.1397)
			(layers "F.Cu" "F.Mask" "F.Paste")
			(net "GND")
			(options
				(clearance outline)
				(anchor circle)
			)
			(primitives
				(gr_poly
					(pts
						(arc
							(start -0.1778 -0.2794)
							(mid -0.249642 -0.249642)
							(end -0.2794 -0.1778)
						)
						(arc
							(start -0.2794 0.1778)
							(mid -0.249642 0.249642)
							(end -0.1778 0.2794)
						)
						(arc
							(start 0.1778 0.2794)
							(mid 0.249642 0.249642)
							(end 0.2794 0.1778)
						)
						(arc
							(start 0.2794 -0.1778)
							(mid 0.249642 -0.249642)
							(end 0.1778 -0.2794)
						)
					)
					(width 0)
					(fill yes)
				)
			)
		)
	)
	(footprint ""
		(layer "F.Cu")
		(at 208.055972 -69.4436 90)
		(property "Reference" "C316"
			(at 0 0 90)
			(layer "F.SilkS")
			(hide yes)
			(effects
				(font
					(size 1.27 1.27)
				)
			)
		)
		(property "Value" "SCD01U16V1KX-GP"
			(at -2.8321 -1.7399 90)
			(unlocked yes)
			(layer "F.Fab")
			(hide yes)
			(effects
				(font
					(size 1.016 1.016)
					(thickness 0.1524)
				)
			)
		)
		(property "Device Type" "C0201H13"
			(at -2.8321 -3.2639 90)
			(unlocked yes)
			(layer "F.Fab")
			(hide yes)
			(effects
				(font
					(size 1.016 1.016)
					(thickness 0.1524)
				)
			)
		)
		(duplicate_pad_numbers_are_jumpers no)
		(fp_rect
			(start -0.2794 0.6477)
			(end 0.2794 -0.6477)
			(stroke
				(width 0)
				(type default)
			)
			(fill no)
			(layer "F.CrtYd")
		)
		(fp_rect
			(start -0.2794 0.6477)
			(end 0.2794 -0.6477)
			(stroke
				(width 0)
				(type default)
			)
			(fill no)
			(layer "F.Fab")
		)
		(pad "1" smd custom
			(at 0 -0.2794 90)
			(size 0.0762 0.0762)
			(layers "F.Cu" "F.Mask" "F.Paste")
			(net "PHY_IOC_TO_CON_B_0_DN_C")
			(options
				(clearance outline)
				(anchor circle)
			)
			(primitives
				(gr_poly
					(pts
						(arc
							(start 0.1524 -0.127)
							(mid 0.137521 -0.162921)
							(end 0.1016 -0.1778)
						)
						(arc
							(start -0.1016 -0.1778)
							(mid -0.137521 -0.162921)
							(end -0.1524 -0.127)
						)
						(arc
							(start -0.1524 0.127)
							(mid -0.137521 0.162921)
							(end -0.1016 0.1778)
						)
						(arc
							(start 0.1016 0.1778)
							(mid 0.137521 0.162921)
							(end 0.1524 0.127)
						)
					)
					(width 0)
					(fill yes)
				)
			)
		)
		(pad "2" smd custom
			(at 0 0.2794 90)
			(size 0.0762 0.0762)
			(layers "F.Cu" "F.Mask" "F.Paste")
			(net "PHY_IOC_TO_CON_B_0_DN")
			(options
				(clearance outline)
				(anchor circle)
			)
			(primitives
				(gr_poly
					(pts
						(arc
							(start 0.1524 -0.127)
							(mid 0.137521 -0.162921)
							(end 0.1016 -0.1778)
						)
						(arc
							(start -0.1016 -0.1778)
							(mid -0.137521 -0.162921)
							(end -0.1524 -0.127)
						)
						(arc
							(start -0.1524 0.127)
							(mid -0.137521 0.162921)
							(end -0.1016 0.1778)
						)
						(arc
							(start 0.1016 0.1778)
							(mid 0.137521 0.162921)
							(end 0.1524 0.127)
						)
					)
					(width 0)
					(fill yes)
				)
			)
		)
	)
	(footprint ""
		(layer "F.Cu")
		(at 83.43392 -134.97052 -90)
		(property "Reference" "R50"
			(at 0 0 270)
			(layer "F.SilkS")
			(hide yes)
			(effects
				(font
					(size 1.27 1.27)
				)
			)
		)
		(property "Value" "4K7R2F-GP"
			(at 0.064008 -3.993896 270)
			(unlocked yes)
			(layer "F.Fab")
			(hide yes)
			(effects
				(font
					(size 1.016 1.016)
					(thickness 0.1524)
				)
			)
		)
		(property "Device Type" "R402H16"
			(at 0.064008 -5.517896 270)
			(unlocked yes)
			(layer "F.Fab")
			(hide yes)
			(effects
				(font
					(size 1.016 1.016)
					(thickness 0.1524)
				)
			)
		)
		(duplicate_pad_numbers_are_jumpers no)
		(fp_line
			(start -0.508 -0.9398)
			(end -0.508 0.9398)
			(stroke
				(width 0.1524)
				(type default)
			)
			(layer "F.SilkS")
		)
		(fp_line
			(start 0.508 -0.9398)
			(end -0.508 -0.9398)
			(stroke
				(width 0.1524)
				(type default)
			)
			(layer "F.SilkS")
		)
		(fp_rect
			(start -0.508 0.9398)
			(end 0.508 -0.9398)
			(stroke
				(width 0)
				(type default)
			)
			(fill no)
			(layer "F.CrtYd")
		)
		(fp_rect
			(start -0.508 0.9398)
			(end 0.508 -0.9398)
			(stroke
				(width 0)
				(type default)
			)
			(fill no)
			(layer "F.Fab")
		)
		(pad "1" smd custom
			(at 0 -0.4445 270)
			(size 0.1397 0.1397)
			(layers "F.Cu" "F.Mask" "F.Paste")
			(net "P3V3_STBY")
			(options
				(clearance outline)
				(anchor circle)
			)
			(primitives
				(gr_poly
					(pts
						(arc
							(start -0.1778 -0.2794)
							(mid -0.249642 -0.249642)
							(end -0.2794 -0.1778)
						)
						(arc
							(start -0.2794 0.1778)
							(mid -0.249642 0.249642)
							(end -0.1778 0.2794)
						)
						(arc
							(start 0.1778 0.2794)
							(mid 0.249642 0.249642)
							(end 0.2794 0.1778)
						)
						(arc
							(start 0.2794 -0.1778)
							(mid 0.249642 -0.249642)
							(end 0.1778 -0.2794)
						)
					)
					(width 0)
					(fill yes)
				)
			)
		)
		(pad "2" smd custom
			(at 0 0.4445 270)
			(size 0.1397 0.1397)
			(layers "F.Cu" "F.Mask" "F.Paste")
			(net "I2C_DEBUG_SDA")
			(options
				(clearance outline)
				(anchor circle)
			)
			(primitives
				(gr_poly
					(pts
						(arc
							(start -0.1778 -0.2794)
							(mid -0.249642 -0.249642)
							(end -0.2794 -0.1778)
						)
						(arc
							(start -0.2794 0.1778)
							(mid -0.249642 0.249642)
							(end -0.1778 0.2794)
						)
						(arc
							(start 0.1778 0.2794)
							(mid 0.249642 0.249642)
							(end 0.2794 0.1778)
						)
						(arc
							(start 0.2794 -0.1778)
							(mid 0.249642 -0.249642)
							(end 0.1778 -0.2794)
						)
					)
					(width 0)
					(fill yes)
				)
			)
		)
	)
	(footprint ""
		(layer "F.Cu")
		(at 47.01159 -158.1912)
		(property "Reference" "R171"
			(at 0 0 0)
			(layer "F.SilkS")
			(hide yes)
			(effects
				(font
					(size 1.27 1.27)
				)
			)
		)
		(property "Value" "0R2J-2-GP"
			(at 0.064008 -3.993896 0)
			(unlocked yes)
			(layer "F.Fab")
			(hide yes)
			(effects
				(font
					(size 1.016 1.016)
					(thickness 0.1524)
				)
			)
		)
		(property "Device Type" "R402H16"
			(at 0.064008 -5.517896 0)
			(unlocked yes)
			(layer "F.Fab")
			(hide yes)
			(effects
				(font
					(size 1.016 1.016)
					(thickness 0.1524)
				)
			)
		)
		(duplicate_pad_numbers_are_jumpers no)
		(fp_line
			(start -0.508 -0.9398)
			(end -0.508 0.9398)
			(stroke
				(width 0.1524)
				(type default)
			)
			(layer "F.SilkS")
		)
		(fp_line
			(start 0.508 -0.9398)
			(end -0.508 -0.9398)
			(stroke
				(width 0.1524)
				(type default)
			)
			(layer "F.SilkS")
		)
		(fp_rect
			(start -0.508 0.9398)
			(end 0.508 -0.9398)
			(stroke
				(width 0)
				(type default)
			)
			(fill no)
			(layer "F.CrtYd")
		)
		(fp_rect
			(start -0.508 0.9398)
			(end 0.508 -0.9398)
			(stroke
				(width 0)
				(type default)
			)
			(fill no)
			(layer "F.Fab")
		)
		(pad "1" smd custom
			(at 0 -0.4445)
			(size 0.1397 0.1397)
			(layers "F.Cu" "F.Mask" "F.Paste")
			(net "I2C_DPB_SCL_OUT")
			(options
				(clearance outline)
				(anchor circle)
			)
			(primitives
				(gr_poly
					(pts
						(arc
							(start -0.1778 -0.2794)
							(mid -0.249642 -0.249642)
							(end -0.2794 -0.1778)
						)
						(arc
							(start -0.2794 0.1778)
							(mid -0.249642 0.249642)
							(end -0.1778 0.2794)
						)
						(arc
							(start 0.1778 0.2794)
							(mid 0.249642 0.249642)
							(end 0.2794 0.1778)
						)
						(arc
							(start 0.2794 -0.1778)
							(mid 0.249642 -0.249642)
							(end 0.1778 -0.2794)
						)
					)
					(width 0)
					(fill yes)
				)
			)
		)
		(pad "2" smd custom
			(at 0 0.4445)
			(size 0.1397 0.1397)
			(layers "F.Cu" "F.Mask" "F.Paste")
			(net "BMC_SMB7_CLK")
			(options
				(clearance outline)
				(anchor circle)
			)
			(primitives
				(gr_poly
					(pts
						(arc
							(start -0.1778 -0.2794)
							(mid -0.249642 -0.249642)
							(end -0.2794 -0.1778)
						)
						(arc
							(start -0.2794 0.1778)
							(mid -0.249642 0.249642)
							(end -0.1778 0.2794)
						)
						(arc
							(start 0.1778 0.2794)
							(mid 0.249642 0.249642)
							(end 0.2794 0.1778)
						)
						(arc
							(start 0.2794 -0.1778)
							(mid 0.249642 -0.249642)
							(end 0.1778 -0.2794)
						)
					)
					(width 0)
					(fill yes)
				)
			)
		)
	)
	(footprint ""
		(layer "F.Cu")
		(at 98.552 -146.431 -90)
		(property "Reference" "R426"
			(at 0 0 270)
			(layer "F.SilkS")
			(hide yes)
			(effects
				(font
					(size 1.27 1.27)
				)
			)
		)
		(property "Value" "0R2J-2-GP"
			(at 0.064008 -3.993896 270)
			(unlocked yes)
			(layer "F.Fab")
			(hide yes)
			(effects
				(font
					(size 1.016 1.016)
					(thickness 0.1524)
				)
			)
		)
		(property "Device Type" "R402H16"
			(at 0.064008 -5.517896 270)
			(unlocked yes)
			(layer "F.Fab")
			(hide yes)
			(effects
				(font
					(size 1.016 1.016)
					(thickness 0.1524)
				)
			)
		)
		(duplicate_pad_numbers_are_jumpers no)
		(fp_line
			(start -0.508 -0.9398)
			(end -0.508 0.9398)
			(stroke
				(width 0.1524)
				(type default)
			)
			(layer "F.SilkS")
		)
		(fp_line
			(start 0.508 -0.9398)
			(end -0.508 -0.9398)
			(stroke
				(width 0.1524)
				(type default)
			)
			(layer "F.SilkS")
		)
		(fp_rect
			(start -0.508 0.9398)
			(end 0.508 -0.9398)
			(stroke
				(width 0)
				(type default)
			)
			(fill no)
			(layer "F.CrtYd")
		)
		(fp_rect
			(start -0.508 0.9398)
			(end 0.508 -0.9398)
			(stroke
				(width 0)
				(type default)
			)
			(fill no)
			(layer "F.Fab")
		)
		(pad "1" smd custom
			(at 0 -0.4445 270)
			(size 0.1397 0.1397)
			(layers "F.Cu" "F.Mask" "F.Paste")
			(net "I2C_DEBUG_SDA_L")
			(options
				(clearance outline)
				(anchor circle)
			)
			(primitives
				(gr_poly
					(pts
						(arc
							(start -0.1778 -0.2794)
							(mid -0.249642 -0.249642)
							(end -0.2794 -0.1778)
						)
						(arc
							(start -0.2794 0.1778)
							(mid -0.249642 0.249642)
							(end -0.1778 0.2794)
						)
						(arc
							(start 0.1778 0.2794)
							(mid 0.249642 0.249642)
							(end 0.2794 0.1778)
						)
						(arc
							(start 0.2794 -0.1778)
							(mid 0.249642 -0.249642)
							(end 0.1778 -0.2794)
						)
					)
					(width 0)
					(fill yes)
				)
			)
		)
		(pad "2" smd custom
			(at 0 0.4445 270)
			(size 0.1397 0.1397)
			(layers "F.Cu" "F.Mask" "F.Paste")
			(net "I2C_DEBUG_SDA_R")
			(options
				(clearance outline)
				(anchor circle)
			)
			(primitives
				(gr_poly
					(pts
						(arc
							(start -0.1778 -0.2794)
							(mid -0.249642 -0.249642)
							(end -0.2794 -0.1778)
						)
						(arc
							(start -0.2794 0.1778)
							(mid -0.249642 0.249642)
							(end -0.1778 0.2794)
						)
						(arc
							(start 0.1778 0.2794)
							(mid 0.249642 0.249642)
							(end 0.2794 0.1778)
						)
						(arc
							(start 0.2794 -0.1778)
							(mid 0.249642 -0.249642)
							(end 0.1778 -0.2794)
						)
					)
					(width 0)
					(fill yes)
				)
			)
		)
	)
	(footprint ""
		(layer "F.Cu")
		(at 39.807134 -131.696968 180)
		(property "Reference" "R378"
			(at 0 0 180)
			(layer "F.SilkS")
			(hide yes)
			(effects
				(font
					(size 1.27 1.27)
				)
			)
		)
		(property "Value" "4K7R2F-GP"
			(at 0.064008 -3.993896 180)
			(unlocked yes)
			(layer "F.Fab")
			(hide yes)
			(effects
				(font
					(size 1.016 1.016)
					(thickness 0.1524)
				)
			)
		)
		(property "Device Type" "R402H16"
			(at 0.064008 -5.517896 180)
			(unlocked yes)
			(layer "F.Fab")
			(hide yes)
			(effects
				(font
					(size 1.016 1.016)
					(thickness 0.1524)
				)
			)
		)
		(duplicate_pad_numbers_are_jumpers no)
		(fp_line
			(start 0.508 -0.9398)
			(end -0.508 -0.9398)
			(stroke
				(width 0.1524)
				(type default)
			)
			(layer "F.SilkS")
		)
		(fp_line
			(start -0.508 -0.9398)
			(end -0.508 0.9398)
			(stroke
				(width 0.1524)
				(type default)
			)
			(layer "F.SilkS")
		)
		(fp_rect
			(start -0.508 0.9398)
			(end 0.508 -0.9398)
			(stroke
				(width 0)
				(type default)
			)
			(fill no)
			(layer "F.CrtYd")
		)
		(fp_rect
			(start -0.508 0.9398)
			(end 0.508 -0.9398)
			(stroke
				(width 0)
				(type default)
			)
			(fill no)
			(layer "F.Fab")
		)
		(pad "1" smd custom
			(at 0 -0.4445 180)
			(size 0.1397 0.1397)
			(layers "F.Cu" "F.Mask" "F.Paste")
			(net "P3V3_STBY")
			(options
				(clearance outline)
				(anchor circle)
			)
			(primitives
				(gr_poly
					(pts
						(arc
							(start -0.1778 -0.2794)
							(mid -0.249642 -0.249642)
							(end -0.2794 -0.1778)
						)
						(arc
							(start -0.2794 0.1778)
							(mid -0.249642 0.249642)
							(end -0.1778 0.2794)
						)
						(arc
							(start 0.1778 0.2794)
							(mid 0.249642 0.249642)
							(end 0.2794 0.1778)
						)
						(arc
							(start 0.2794 -0.1778)
							(mid 0.249642 -0.249642)
							(end 0.1778 -0.2794)
						)
					)
					(width 0)
					(fill yes)
				)
			)
		)
		(pad "2" smd custom
			(at 0 0.4445 180)
			(size 0.1397 0.1397)
			(layers "F.Cu" "F.Mask" "F.Paste")
			(net "BMC_GPIOZ6")
			(options
				(clearance outline)
				(anchor circle)
			)
			(primitives
				(gr_poly
					(pts
						(arc
							(start -0.1778 -0.2794)
							(mid -0.249642 -0.249642)
							(end -0.2794 -0.1778)
						)
						(arc
							(start -0.2794 0.1778)
							(mid -0.249642 0.249642)
							(end -0.1778 0.2794)
						)
						(arc
							(start 0.1778 0.2794)
							(mid 0.249642 0.249642)
							(end 0.2794 0.1778)
						)
						(arc
							(start 0.2794 -0.1778)
							(mid 0.249642 -0.249642)
							(end 0.1778 -0.2794)
						)
					)
					(width 0)
					(fill yes)
				)
			)
		)
	)
)
